M48
INCH,TZ
T01C.016
T02C.037
T03C.041
T04C.14
T05C.158
T06C.034
T07C.086
T08C.158
;LEADER: 12 
;HEADER: 
;CODE  : ASCII 
;FILE  : 12523-1-1-4.drl for board 12523-1.brd ... layers TOP and BOTTOM
;T01 Holesize 1. = 16.000000 Tolerance = +0.000000/-0.000000 PLATED MILS Quantity = 789
;T02 Holesize 2. = 37.000000 Tolerance = +0.000000/-0.000000 PLATED MILS Quantity = 3
;T03 Holesize 3. = 41.000000 Tolerance = +0.000000/-0.000000 PLATED MILS Quantity = 52
;T04 Holesize 4. = 140.000000 Tolerance = +0.000000/-0.000000 PLATED MILS Quantity = 2
;T05 Holesize 5. = 158.000000 Tolerance = +0.000000/-0.000000 PLATED MILS Quantity = 2
;T06 Holesize 6. = 34.000000 Tolerance = +0.000000/-0.000000 NON_PLATED MILS Quantity = 2
;T07 Holesize 7. = 86.000000 Tolerance = +0.000000/-0.000000 NON_PLATED MILS Quantity = 3
;T08 Holesize 8. = 158.000000 Tolerance = +0.000000/-0.000000 NON_PLATED MILS Quantity = 2
%
G90
T01
X16419Y6482
Y26482
X36419
Y6482
X136419
X156419
Y26482
X176419Y6482
Y26482
X196419Y6482
Y26482
X216419
Y6482
X236419
Y26482
X256419Y6482
Y26482
X276419Y6482
Y26482
X296419Y6482
Y26482
X316419
Y6482
X336419Y26482
Y6482
X356419
Y26482
X376419Y6482
Y26482
X396419Y6482
Y26482
X416419Y6482
Y26482
X436419Y6482
X516419
X533619Y26482
Y6482
X550819
Y26482
X568019Y6482
Y26482
X585219
Y6482
X602419
Y26482
X619619Y6482
Y26482
X634119Y6482
Y26482
Y46482
X619619
X602419
X585219
X568019
X550819
X533619
X516419
X496419
X476419
X456419
X436419
X416419
X396419
X376419
X356419
X336419
X316419
X296419
X276419
X256419
X236419
X216419
X196419
X176419
X156419
X136419
X116419
X96419
X76419
X56419
X16419Y86482
X36419
X56419
Y66482
X76419
Y86482
X96419
Y66482
X116419Y86482
Y66482
X136419Y86482
Y66482
X156419
Y86482
X176419Y66482
Y86482
X196419Y66482
Y86482
X216419
Y66482
X236419
Y86482
X256419
Y66482
X273500Y66500
X274500Y86500
X301000
X302000Y67000
X316419Y66482
Y86482
X336419
Y66482
X356419
Y86482
X376419
Y66482
X396419Y86482
Y66482
X416419
Y86482
X436419Y66482
Y86482
X456419Y66482
Y86482
X476419Y66482
Y86482
X496419
Y66482
X516419Y86482
Y66482
X536419
Y86482
X556419
Y66482
X573623Y66967
X584543Y86671
X611253Y65701
X611398Y86936
X626500Y78500
X633753Y65701
X633898Y86936
X628500Y104000
X616000Y115500
X594500Y117000
X576419Y106482
X556419
X536419
X516419
X496419
X476419
X456419
X436419
X416419
X396419
X376419
X356419
X336419
X316419
X300000Y106500
X274500
X256419Y106482
X236419
X216419
X196419
X176419
X156419
X136419
X116419
X96419
X76419
X56419
X36419
X26419Y116482
X16419
Y106482
X6419Y116482
X-3350Y117504
X-3581Y136482
Y126482
Y146482
X6419Y126482
Y146482
Y136482
X16419
Y146482
Y126482
X26419Y146482
Y126482
Y136482
X36419Y126482
Y146482
X56419
Y126482
X76419Y146482
Y126482
X96419
Y146482
X116419Y126482
Y146482
X136419
Y126482
X156419Y146482
Y126482
X176419Y146482
Y126482
X196419Y146482
Y126482
X216419Y146482
Y126482
X236419
Y146482
X256419Y126482
Y146482
X276419Y126482
Y146482
X296419Y126482
Y146482
X316419
Y126482
X336419Y146482
Y126482
X356419Y146482
Y126482
X376419
Y146482
X396419
Y126482
X416419
Y146482
X436419
Y126482
X456419
Y146482
X476419Y126482
Y146482
X496419
Y126482
X516419Y146482
Y126482
X536419Y146482
Y126482
X556419
Y146482
X576419Y126482
X607000Y123500
X616000Y138000
X634000Y123500
X616000Y173500
X552924Y170924
Y175124
X548724Y170924
Y175124
X544476Y165522
Y161322
X540276
Y165522
X536076
Y161322
X531876Y165522
Y161322
X527711Y175174
Y170974
X523511Y175174
Y170974
X519221Y160912
Y165112
X515021
Y160912
X510821Y165112
Y160912
X506621
Y165112
X502595Y174685
Y170485
X498395Y174685
Y170485
X493843Y160670
Y164870
X489643
Y160670
X485443Y164870
Y160670
X481243
Y164870
X477284Y170386
Y174586
X473084
Y170386
X465500Y175000
Y170800
X461300Y175000
Y170800
X457100
Y175000
X456500Y166500
X452500Y174500
Y170300
X448300
Y174500
X444100Y170300
Y174500
X439500
Y170300
X436500Y166000
X435300Y170300
Y174500
X431100
Y170300
X425919Y170282
Y174482
X421719Y170282
Y174482
X417519
Y170282
X416500Y166000
X396419Y166482
X380000Y166500
X354500
X338500Y166000
X317000Y166500
X295500Y169000
X276419Y166482
X251500Y166500
X236419Y166482
X216419
X196419
X176419
X156419
X136419
X116419
X96419
X76419
X56419
X36419
X26419
Y156482
Y176482
X16419Y166482
Y176482
Y156482
X6419Y176482
Y166482
Y156482
X-3581Y166482
Y156482
Y176482
X-2602Y206936
X7398
X16419Y186482
X17398Y206936
X26419Y186482
X27398Y206936
X36419Y186482
X37398Y206936
X56419Y186482
X57398Y206936
X76419Y186482
X77398Y206936
X96419Y186482
X97398Y206936
X116419Y186482
X117398Y206936
X136419Y186482
X137398Y206936
X156419Y186482
X157398Y206936
X176419Y186482
X177398Y206436
X196419Y186482
X197398Y206436
X216419Y186482
X217398Y206436
X236419Y186482
X237398Y206436
X256419Y186482
X257398Y206436
X275500Y186500
X277398Y206436
X296419Y186482
X297398Y206436
X317398
X317500Y186500
X336419Y186482
X337398Y206436
X357398
X357500Y186500
X376419Y186482
X377398Y206436
X396419Y186482
X397398Y206436
X417398
X418300Y197500
Y201700
X422500
Y197500
X426700
Y201700
X431300
Y197500
X435500
Y201700
X437398Y206436
X439700Y201700
Y197500
X444800Y201700
Y197500
X449000Y201700
Y197500
X453200
Y201700
X457398Y206436
X457800Y197500
Y201700
X462000
Y197500
X466200Y201700
Y197500
X472887Y196972
Y201172
X477087Y196972
Y201172
X480311Y206602
X484511
X488711
X492911
X498052Y200389
Y196189
X502252Y200389
Y196189
X506135Y206357
X510335
X514535
X518735
X523561Y200632
Y196432
X527761Y200632
Y196432
X531877Y206189
X536077
X540277
X544477
X548971Y200877
Y196677
X553171
Y200877
X615500Y199000
X615898Y224436
X561500Y232000
X557000Y231500
X544477Y210389
X540898Y228436
X540277Y210389
X536077
X531877
X520898Y228436
X518735Y210557
X514535
X510335
X506135
X497398Y226936
X492911Y210802
X488711
X484511
X480311
X477398Y226936
X457398
X437398
X417398
X397398
X377398
X357398
X337398
X317398
X297398
X277398
X257398
X237398
X217398
X197398
X177398
X157398
X137398
X117398
X97398
X77398
X57398
X36769
X27398Y216936
X17398
X7398Y236936
Y216936
Y226936
X-2602Y216936
Y226936
Y236936
Y266936
Y256936
Y246936
X7398Y266936
Y256936
Y246936
X17398Y266936
Y256936
X27398Y266936
Y256936
X36769Y246936
X37398Y266936
X57398
Y246936
X77398Y266936
Y246936
X97398Y266936
Y246936
X116398Y266936
X117398Y246936
X137398Y266936
Y246936
X157398
Y266936
X177398
Y246936
X197398Y266936
Y246936
X217398
Y266936
X237398Y246936
Y266936
X257398
Y246936
X277398Y266936
Y246936
X297398
Y266936
X317398
Y246936
X337398Y266936
Y246936
X357398
Y266936
X377398Y246936
Y266936
X397398Y246936
Y266936
X417398Y246936
X418398Y266936
X437398Y246936
Y266936
X457398Y246936
Y266936
X477398Y246936
Y266936
X497398Y246936
X546600Y257971
X560500Y268000
X615398Y266436
X615898Y244436
X615398Y284436
X600000Y298500
X561500Y298000
X559996Y282972
X534000Y282000
X457398Y286936
X437398
X418398
X397398
X377398
X357398
X337398
X317398
X300398
X279398
X257398
X237398
X217398
X197398
X177398
X157398
X137398
X116398
X97398
X77398
X57398
X37398
X27398Y276936
Y286936
X17398
Y276936
X7398
Y286936
X-2602Y276936
X-7102Y327202
X-6940Y316247
X-2948Y302202
X-2602Y316436
X2334Y318654
X3398Y326936
X64398Y304436
X86398Y303936
X492000Y321000
X506500Y305500
X512500Y323000
X520381Y300757
X525161Y311000
X537136Y326402
X543900Y314000
X549500Y305500
X577500Y305000
X587500Y318500
X616498Y316236
X633398Y325436
X630000Y345500
X600000Y337500
Y342000
X595500Y337500
Y342000
X520500Y331000
X495398Y338436
Y358436
X475398
Y338436
X455398
Y358436
X435398
Y338436
X415330Y357964
Y337964
X395330Y357964
Y337964
X375330Y357964
Y337964
X355330
Y357964
X335330Y337964
Y357964
X315330Y337964
Y357964
X295330Y337964
Y357964
X275330Y337964
Y357964
X255330Y337964
Y357964
X235330
Y337964
X215330Y357964
Y337964
X195330Y357964
Y337964
X175330Y357964
Y337964
X155330Y357964
Y337964
X135330Y357964
Y337964
X115330Y357964
Y337964
X96398Y337936
X95330Y357964
X78398Y358436
X77898Y338436
X62398
X61898Y358936
X57398Y348682
X52705Y348626
X48325Y348514
X34898Y344936
X30923Y335665
X26723
X25500Y353000
X25000Y343000
X10000Y332000
X5694Y343705
X1494
X-6602Y347202
Y357202
X-7102Y337202
X6398Y369936
X6898Y387436
X22000Y387500
Y374500
X33986Y362933
X37500Y386500
X95330Y377964
X115330
X135330
X155330
X175330
X195330
X215330
X235330
X255330
X275330
X295330
X315330
X335330
X355330
X375330
X395330
X415330
X435398Y378436
X455398
X475398
X495398
X630000Y387500
X632898Y404936
X617798Y413000
X612798
X499000Y418500
X477000Y418000
X455330Y417964
X435330
X415330
X395330
X375330
X355330
X335330
X315330
X295330
X275330
X255330
X235330
X215330
X195330
X175330
X155330
X135330
X115330
X95330
X75500Y417500
X60052Y394674
X55500Y417000
X55352Y394674
X51094Y394478
X6898Y445436
X35830Y442464
X62000Y442500
X85330Y442964
X105330
X132000Y442500
X155000Y442000
X175500
X196000Y442500
X215830Y442464
X235830
X255830
X275830
X295830
X315830
X335830
X355830
X375830
X395830
X415830
X435830
X455830
X485510Y442620
X505510
X610898Y425436
Y445436
X632898Y424936
Y444936
Y464936
X610898Y465436
X519898
X499898
X479898
X459898
X439898
X419898
X399898
X379898
X359898
X339898
X319898
X299898
X279898
X259898
X239898
X219898
X199898
X179898
X159898
X139898
X117500Y465500
X91500
X67830Y465464
X39898Y465436
X19898
X6898
T02
X596102Y66929
X602008Y74803
X596102Y82677
T03
X570709Y161889
X580709
X590709
X600709
Y171889
X590709
X580709
X570709
Y181889
X580709
X590709
X600709
Y191889
X590709
X580709
X570709
Y204409
X580709
X590709
X600709
Y214409
X590709
X580709
X570709
Y224409
X580709
X590709
X600709
Y234409
X590709
X580709
X570709
Y244409
X580709
X590709
X600709
Y256929
X590709
X580709
X570709
Y266929
X580709
X590709
X600709
Y276929
X590709
X580709
X570709
Y286929
X580709
X590709
X600709
T04
X30157Y61023
Y415354
T05
X498661Y23622
X589212Y448818
T06
X599055Y59055
Y90551
T07
X-23621Y15748
Y937008
X1312285Y15747
T08
X600709Y136909
Y311909
M30
